# S9S_MB_2U (Grand Teton) — schematic netlist excerpt (pin names and nets, part order shuffled) for the footprints in the layout excerpt that follows; sources: Cadence DE-HDL packaged netlist, KiCad conversion of 03242023_DA0F0TMBIJ0_F0T_Motherboard_J_brd_V01_OCP.brd

R3096  Q_RES  130 1% CHIP  pkg 0402LF  page 254 : A = LED_PWRGD_PVCCFA_EHV_CPU1 ; B = P3V3_AUX
PC2348  Q_CAP  1NF 50V 10% EMPTY  pkg 0402  page 302 : A = HSC_OCREF ; B = AGND_HSC

(kicad_pcb
	(version 20260206)
	(generator "pcbnew")
	(generator_version "10.0")
	(general
		(thickness 1.6)
		(legacy_teardrops no)
	)
	(paper "A4")
	(title_block
		(title "03242023_DA0F0TMBIJ0_F0T_Motherboard_J_brd_V01_OCP.brd")
		(comment 1 "Grand Teton / footprints 2482-2483 of 6105")
	)
	(layers
		(0 "F.Cu" signal "TOP")
		(4 "In1.Cu" signal "GND")
		(6 "In2.Cu" signal "IN1")
		(8 "In3.Cu" signal "GND1")
		(10 "In4.Cu" signal "IN2")
		(12 "In5.Cu" signal "GND2")
		(14 "In6.Cu" signal "IN3")
		(16 "In7.Cu" signal "GND3")
		(18 "In8.Cu" signal "VCC")
		(20 "In9.Cu" signal "VCC1")
		(22 "In10.Cu" signal "GND4")
		(24 "In11.Cu" signal "IN4")
		(26 "In12.Cu" signal "GND5")
		(28 "In13.Cu" signal "IN5")
		(30 "In14.Cu" signal "GND6")
		(32 "In15.Cu" signal "IN6")
		(34 "In16.Cu" signal "GND7")
		(2 "B.Cu" signal "BOTTOM")
		(9 "F.Adhes" user "F.Adhesive")
		(11 "B.Adhes" user "B.Adhesive")
		(13 "F.Paste" user "Package Geometry/Pastemask Top")
		(15 "B.Paste" user "Package Geometry/Pastemask Bottom")
		(5 "F.SilkS" user "Ref Des/Silkscreen Top")
		(7 "B.SilkS" user "Ref Des/Silkscreen Bottom")
		(1 "F.Mask" user "Board Geometry/Soldermask Top")
		(3 "B.Mask" user "Board Geometry/Soldermask Bottom")
		(17 "Dwgs.User" user "User.Drawings")
		(19 "Cmts.User" user "User.Comments")
		(21 "Eco1.User" user "User.Eco1")
		(23 "Eco2.User" user "User.Eco2")
		(25 "Edge.Cuts" user "Board Geometry/Outline")
		(27 "Margin" user)
		(31 "F.CrtYd" user "Package Geometry/Place Bound Top")
		(29 "B.CrtYd" user "Package Geometry/Place Bound Bottom")
		(35 "F.Fab" user "Ref Des/Assembly Top")
		(33 "B.Fab" user "Ref Des/Assembly Bottom")
	)
	(footprint ""
		(layer "F.Cu")
		(at 74.615802 -74.901552 -90)
		(property "Reference" "R3096"
			(at 0 0 270)
			(layer "F.SilkS")
			(hide yes)
			(effects
				(font
					(size 1.27 1.27)
				)
			)
		)
		(property "Value" ""
			(at 0 0 270)
			(layer "F.Fab")
			(effects
				(font
					(size 1.27 1.27)
				)
			)
		)
		(duplicate_pad_numbers_are_jumpers no)
		(fp_line
			(start -0.7874 0.4064)
			(end -0.7874 -0.4064)
			(stroke
				(width 0.1524)
				(type default)
			)
			(layer "F.SilkS")
		)
		(fp_line
			(start 0.7874 0.4064)
			(end -0.7874 0.4064)
			(stroke
				(width 0.1524)
				(type default)
			)
			(layer "F.SilkS")
		)
		(fp_line
			(start -0.7874 -0.4064)
			(end 0.7874 -0.4064)
			(stroke
				(width 0.1524)
				(type default)
			)
			(layer "F.SilkS")
		)
		(fp_line
			(start 0.7874 -0.4064)
			(end 0.7874 0.4064)
			(stroke
				(width 0.1524)
				(type default)
			)
			(layer "F.SilkS")
		)
		(fp_line
			(start -0.67945 0.3048)
			(end -0.67945 -0.305054)
			(stroke
				(width 0.1)
				(type default)
			)
			(layer "F.Fab")
		)
		(fp_line
			(start -0.12065 0.3048)
			(end -0.67945 0.3048)
			(stroke
				(width 0.1)
				(type default)
			)
			(layer "F.Fab")
		)
		(fp_line
			(start 0.120396 0.3048)
			(end 0.120396 0.2794)
			(stroke
				(width 0.1)
				(type default)
			)
			(layer "F.Fab")
		)
		(fp_line
			(start 0.67945 0.3048)
			(end 0.120396 0.3048)
			(stroke
				(width 0.1)
				(type default)
			)
			(layer "F.Fab")
		)
		(fp_line
			(start -0.12065 0.2794)
			(end -0.12065 0.3048)
			(stroke
				(width 0.1)
				(type default)
			)
			(layer "F.Fab")
		)
		(fp_line
			(start 0.120396 0.2794)
			(end -0.12065 0.2794)
			(stroke
				(width 0.1)
				(type default)
			)
			(layer "F.Fab")
		)
		(fp_line
			(start -0.12065 -0.2794)
			(end 0.12065 -0.2794)
			(stroke
				(width 0.1)
				(type default)
			)
			(layer "F.Fab")
		)
		(fp_line
			(start 0.12065 -0.2794)
			(end 0.12065 -0.3048)
			(stroke
				(width 0.1)
				(type default)
			)
			(layer "F.Fab")
		)
		(fp_line
			(start 0.12065 -0.3048)
			(end 0.67945 -0.3048)
			(stroke
				(width 0.1)
				(type default)
			)
			(layer "F.Fab")
		)
		(fp_line
			(start 0.67945 -0.3048)
			(end 0.67945 0.3048)
			(stroke
				(width 0.1)
				(type default)
			)
			(layer "F.Fab")
		)
		(fp_line
			(start -0.67945 -0.305054)
			(end -0.12065 -0.305054)
			(stroke
				(width 0.1)
				(type default)
			)
			(layer "F.Fab")
		)
		(fp_line
			(start -0.12065 -0.305054)
			(end -0.12065 -0.2794)
			(stroke
				(width 0.1)
				(type default)
			)
			(layer "F.Fab")
		)
		(pad "1" smd circle
			(at -0.40005 0 270)
			(size 0 0)
			(layers "F.Cu" "F.Mask" "F.Paste")
			(net "LED_PWRGD_PVCCFA_EHV_CPU1")
		)
		(pad "2" smd circle
			(at 0.40005 0 270)
			(size 0 0)
			(layers "F.Cu" "F.Mask" "F.Paste")
			(net "P3V3_AUX")
		)
	)
	(footprint ""
		(layer "F.Cu")
		(at 205.397608 -399.743422 180)
		(property "Reference" "PC2348"
			(at 0 0 180)
			(layer "F.SilkS")
			(hide yes)
			(effects
				(font
					(size 1.27 1.27)
				)
			)
		)
		(property "Value" ""
			(at 0 0 180)
			(layer "F.Fab")
			(effects
				(font
					(size 1.27 1.27)
				)
			)
		)
		(duplicate_pad_numbers_are_jumpers no)
		(fp_line
			(start 0.7874 0.4064)
			(end -0.7874 0.4064)
			(stroke
				(width 0.1524)
				(type default)
			)
			(layer "F.SilkS")
		)
		(fp_line
			(start 0.7874 -0.4064)
			(end 0.7874 0.4064)
			(stroke
				(width 0.1524)
				(type default)
			)
			(layer "F.SilkS")
		)
		(fp_line
			(start -0.7874 0.4064)
			(end -0.7874 -0.4064)
			(stroke
				(width 0.1524)
				(type default)
			)
			(layer "F.SilkS")
		)
		(fp_line
			(start -0.7874 -0.4064)
			(end 0.7874 -0.4064)
			(stroke
				(width 0.1524)
				(type default)
			)
			(layer "F.SilkS")
		)
		(fp_line
			(start 0.67945 0.3048)
			(end 0.120396 0.3048)
			(stroke
				(width 0.1)
				(type default)
			)
			(layer "F.Fab")
		)
		(fp_line
			(start 0.67945 -0.3048)
			(end 0.67945 0.3048)
			(stroke
				(width 0.1)
				(type default)
			)
			(layer "F.Fab")
		)
		(fp_line
			(start 0.12065 -0.2794)
			(end 0.12065 -0.3048)
			(stroke
				(width 0.1)
				(type default)
			)
			(layer "F.Fab")
		)
		(fp_line
			(start 0.12065 -0.3048)
			(end 0.67945 -0.3048)
			(stroke
				(width 0.1)
				(type default)
			)
			(layer "F.Fab")
		)
		(fp_line
			(start 0.120396 0.3048)
			(end 0.120396 0.2794)
			(stroke
				(width 0.1)
				(type default)
			)
			(layer "F.Fab")
		)
		(fp_line
			(start 0.120396 0.2794)
			(end -0.12065 0.2794)
			(stroke
				(width 0.1)
				(type default)
			)
			(layer "F.Fab")
		)
		(fp_line
			(start -0.12065 0.3048)
			(end -0.67945 0.3048)
			(stroke
				(width 0.1)
				(type default)
			)
			(layer "F.Fab")
		)
		(fp_line
			(start -0.12065 0.2794)
			(end -0.12065 0.3048)
			(stroke
				(width 0.1)
				(type default)
			)
			(layer "F.Fab")
		)
		(fp_line
			(start -0.12065 -0.2794)
			(end 0.12065 -0.2794)
			(stroke
				(width 0.1)
				(type default)
			)
			(layer "F.Fab")
		)
		(fp_line
			(start -0.12065 -0.305054)
			(end -0.12065 -0.2794)
			(stroke
				(width 0.1)
				(type default)
			)
			(layer "F.Fab")
		)
		(fp_line
			(start -0.67945 0.3048)
			(end -0.67945 -0.305054)
			(stroke
				(width 0.1)
				(type default)
			)
			(layer "F.Fab")
		)
		(fp_line
			(start -0.67945 -0.305054)
			(end -0.12065 -0.305054)
			(stroke
				(width 0.1)
				(type default)
			)
			(layer "F.Fab")
		)
		(pad "1" smd circle
			(at -0.40005 0 180)
			(size 0 0)
			(layers "F.Cu" "F.Mask" "F.Paste")
			(net "HSC_OCREF")
		)
		(pad "2" smd circle
			(at 0.40005 0 180)
			(size 0 0)
			(layers "F.Cu" "F.Mask" "F.Paste")
			(net "AGND_HSC")
		)
	)
)
